FILE_TYPE = CONNECTIVITY;
{Allegro Design Entry HDL 17.2-2016 S081 (4005846) 1/11/2022}
"PAGE_NUMBER" = 257;
0"NC";
1"P5V\g";
2"P5V\g";
3"P3V3\g";
4"P3V3\g";
5"SW_P12V_PVCCFA_EHV_FIVRA_CPU0_L\g";
6"PVCCFA_EHV_FIVRA_CPU0\g";
7"PVCCFA_EHV_FIVRA_CPU0\g";
8"SW_P12V_PVCCFA_EHV_FIVRA_CPU0_R\g";
9"P12V_AUX\g";
10"PVCCFA_EHV_FIVRA_CPU0\g";
11"SW_P12V_PVCCFA_EHV_FIVRA_CPU0_L\g";
12"GND\g";
13"GND\g";
14"GND\g";
15"GND\g";
16"GND\g";
17"GND\g";
18"GND\g";
19"GND\g";
20"GND\g";
21"GND\g";
22"GND\g";
23"GND\g";
24"GND\g";
25"GND\g";
26"GND\g";
27"GND\g";
28"GND\g";
29"PVCCFA_EHV_FIVRA_CPU0_VDD1"CDS_PHYS_NET_NAME"PVCCFA_EHV_FIVRA_CPU0_VDD1";
30"SW_PVCCFA_EHV_FIVRA_CPU0_SW2";
31"SW_PVCCFA_EHV_FIVRA_CPU0_BOOTR2";
32"SW_PVCCFA_EHV_FIVRA_CPU0_BOOT2_R";
33"PVCCFA_EHV_FIVRA_CPU0_VOS1";
34"SW_PVCCFA_EHV_FIVRA_CPU0_BOOT1_R";
35"SW_PVCCFA_EHV_FIVRA_CPU0_SW1";
36"PVCCFA_EHV_FIVRA_CPU0_VOS2";
37"SW_PVCCFA_EHV_FIVRA_CPU0_BOOTR1";
38"SW_PVCCFA_EHV_FIVRA_CPU0_BOOT1";
39"PVCCFA_EHV_FIVRA_CPU0_PVCC1";
40"PVCCIN_CPU0_VREF"CDS_PHYS_NET_NAME"PVCCIN_CPU0_VREF";
41"PVCCFA_EHV_FIVRA_CPU0_IMON1";
42"PVCCFA_EHV_FIVRA_CPU0_BTSEN";
43"SW_PVCCFA_EHV_FIVRA_CPU0_BOOT2";
44"PVCCFA_EHV_FIVRA_CPU0_PVCC2";
45"PVCCFA_EHV_FIVRA_CPU0_PWM1";
46"PVCCFA_EHV_FIVRA_CPU0_VDD2"CDS_PHYS_NET_NAME"PVCCFA_EHV_FIVRA_CPU0_VDD2";
47"PVCCIN_CPU0_VREF"CDS_PHYS_NET_NAME"PVCCIN_CPU0_VREF";
48"PVCCFA_EHV_FIVRA_CPU0_IMON2";
49"PVCCFA_EHV_FIVRA_CPU0_BTSEN";
50"PVCCFA_EHV_FIVRA_CPU0_PWM2";
51"PVCCFA_EHV_FIVRA_CPU0_LSET1"CDS_PHYS_NET_NAME"PVCCFA_EHV_FIVRA_CPU0_LSET1";
52"PVCCFA_EHV_FIVRA_CPU0_LSET2";
%"UNIVERSAL_GND"
"1","(-4750,1675)","0","logical_power","I1";
;
HDL_POWER"GND"
CDS_LIB"logical_power";
"A"12;
%"VCC15"
"1","(-4825,6925)","0","logical_power","I10";
;
HDL_POWER"P5V"
CDS_LIB"logical_power";
"A"2;
%"Q_CAP"
"2","(-3975,2200)","0","pure_quanta","I15";
;
PART_NUMBER"CH4104K1B00"
TOLERANCE"10%"
MATERIAL"X7R"
PACK_TYPE"0402"
VOLTAGE"25V"
VALUE"0.1UF"
LOCATION"PC1350"
CDS_LIB"pure_quanta"
$SEC"1"
CDS_SEC"1";
"A"
$PN"1"13;
"B"
$PN"2"47;
%"ISL99390FRZTR5935"
"1","(-2725,2400)","0","pure_quanta","I16";
;
PART_NUMBER"AL099390004"
MATERIAL"IC"
VALUE"ISL99390FRZ-TR5935"
PART_TYPE"SMLF"
LOCATION"PU70_P0_2"
NEEDS_NO_SIZE"TRUE"
CDS_LMAN_SYM_OUTLINE"-300,700,250,-650"
CDS_LIB"pure_quanta"
$SEC"1"
CDS_SEC"1";
"PGND2"
$PN"7_9-20_24"18;
"GL2"
$PN"41"0;
"GL1"
$PN"6"0;
"DNC"
$PN"31"0;
"EN"
$PN"35"46;
"PGND3"
$PN"40"18;
"VOS"
$PN"1"36;
"VIN2"
$PN"30"5;
"PGND1"
$PN"5"18;
"SW"
$PN"10_19"30;
"LSET"
$PN"37"52;
"IOUT"
$PN"38"48;
"TOUT_FLT"
$PN"36"49;
"PVCC"
$PN"4"44;
"PHASE"
$PN"32"31;
"VIN1"
$PN"25_29"5;
"BOOT"
$PN"33"43;
"AGND"
$PN"2"18;
"VCC"
$PN"3"46;
"REFIN"
$PN"39"47;
"PWM"
$PN"34"50;
%"UNIVERSAL_GND"
"1","(-4250,2600)","0","logical_power","I17";
;
HDL_POWER"GND"
CDS_LIB"logical_power";
"A"16;
%"Q_CAP"
"1","(-4250,2850)","0","pure_quanta","I18";
;
PART_NUMBER"CH5222KEB01"
PACK_TYPE"C0402"
VOLTAGE"10V"
VALUE"2.2UF"
TOLERANCE"10%"
MATERIAL"X6S"
LOCATION"PC601"
CDS_LIB"pure_quanta"
LOCATION"PC601"
$SEC"1"
CDS_SEC"1";
"B"
$PN"2"16;
"A"
$PN"1"46;
%"Q_RES"
"2","(-4250,3250)","0","pure_quanta","I19";
;
PART_NUMBER"CS-2202FB01"
VALUE"2.2"
WATTAGE"1/16W"
TOLERANCE"1%"
MATERIAL"CHIP"
PACK_TYPE"0402LF"
LOCATION"PR356"
CDS_LIB"pure_quanta"
LOCATION"PR356"
$SEC"1"
CDS_SEC"1";
"A"
$PN"1"44;
"B"
$PN"2"46;
%"Q_RES"
"2","(-4750,1900)","2","pure_quanta","I2";
;
PART_NUMBER"CS28872FB01"
PACK_TYPE"0402LF"
MATERIAL"EMPTY"
WATTAGE"1/16W"
VALUE"8.87K"
TOLERANCE"1%"
LOCATION"PR353"
CDS_LIB"pure_quanta"
LOCATION"PR353"
$SEC"1"
CDS_SEC"1";
"A"
$PN"1"52;
"B"
$PN"2"12;
%"UNIVERSAL_GND"
"1","(-3725,3000)","0","logical_power","I20";
;
HDL_POWER"GND"
CDS_LIB"logical_power";
"A"17;
%"Q_CAP"
"1","(-3725,3250)","0","pure_quanta","I21";
;
PART_NUMBER"CH5222KEB01"
VALUE"2.2UF"
VOLTAGE"10V"
TOLERANCE"10%"
MATERIAL"X6S"
PACK_TYPE"C0402"
LOCATION"PC1212_P0_2"
CDS_LIB"pure_quanta"
$SEC"1"
CDS_SEC"1";
"B"
$PN"2"17;
"A"
$PN"1"44;
%"Q_RES"
"2","(-4175,3900)","0","pure_quanta","I22";
;
PART_NUMBER"CS00002JB13"
VALUE"0"
WATTAGE"1/16W"
PACK_TYPE"0402LF"
TOLERANCE"5%"
MATERIAL"EMPTY"
LOCATION"PR633"
CDS_LIB"pure_quanta"
$SEC"1"
CDS_SEC"1";
"A"
$PN"1"3;
"B"
$PN"2"44;
%"VCC15"
"1","(-4175,4125)","0","logical_power","I23";
;
HDL_POWER"P3V3"
CDS_LIB"logical_power";
"A"3;
%"ISL99390FRZTR5935"
"1","(-2725,5200)","0","pure_quanta","I25";
;
PART_NUMBER"AL099390004"
VALUE"ISL99390FRZ-TR5935"
MATERIAL"IC"
PART_TYPE"SMLF"
LOCATION"PU69_P0_1"
NEEDS_NO_SIZE"TRUE"
CDS_LMAN_SYM_OUTLINE"-300,700,250,-650"
CDS_LIB"pure_quanta"
$SEC"1"
CDS_SEC"1";
"PGND2"
$PN"7_9-20_24"19;
"GL2"
$PN"41"0;
"GL1"
$PN"6"0;
"DNC"
$PN"31"0;
"EN"
$PN"35"29;
"PGND3"
$PN"40"19;
"VOS"
$PN"1"33;
"VIN2"
$PN"30"8;
"PGND1"
$PN"5"19;
"SW"
$PN"10_19"35;
"LSET"
$PN"37"51;
"IOUT"
$PN"38"41;
"TOUT_FLT"
$PN"36"42;
"PVCC"
$PN"4"39;
"PHASE"
$PN"32"37;
"VIN1"
$PN"25_29"8;
"BOOT"
$PN"33"38;
"AGND"
$PN"2"19;
"VCC"
$PN"3"29;
"REFIN"
$PN"39"40;
"PWM"
$PN"34"45;
%"UNIVERSAL_GND"
"1","(-2075,1675)","0","logical_power","I26";
;
HDL_POWER"GND"
CDS_LIB"logical_power";
"A"18;
%"Q_CAP"
"1","(-1925,3300)","0","pure_quanta","I27";
;
PART_NUMBER"TMP_QCH2336K1B12"
MATERIAL"X7R"
PACK_TYPE"0402"
VOLTAGE"50V"
VALUE"3300PF"
TOLERANCE"10%"
LOCATION"PC603_P0_2"
CDS_LIB"pure_quanta"
LOCATION"PC603_P0_2"
$SEC"1"
CDS_SEC"1";
"B"
$PN"2"22;
"A"
$PN"1"5;
%"Q_CAP"
"1","(-1525,3300)","0","pure_quanta","I28";
;
PART_NUMBER"CH5103KEB01"
TOLERANCE"10%"
PACK_TYPE"C0402"
VOLTAGE"16V"
VALUE"1UF"
MATERIAL"X6S"
LOCATION"PC605_P0_2"
CDS_LIB"pure_quanta"
LOCATION"PC605_P0_2"
$SEC"1"
CDS_SEC"1";
"B"
$PN"2"22;
"A"
$PN"1"5;
%"UNIVERSAL_GND"
"1","(-2075,4475)","0","logical_power","I29";
;
HDL_POWER"GND"
CDS_LIB"logical_power";
"A"19;
%"UNIVERSAL_GND"
"1","(-4800,2125)","0","logical_power","I3";
;
HDL_POWER"GND"
CDS_LIB"logical_power";
"A"13;
%"Q_RES"
"1","(-1225,2850)","0","pure_quanta","I30";
;
PART_NUMBER"CS-3302FB01"
VALUE"3.3"
WATTAGE"1/16W"
PACK_TYPE"0402LF"
MATERIAL"CHIP"
TOLERANCE"1%"
LOCATION"PR1781"
CDS_LIB"pure_quanta"
$SEC"1"
CDS_SEC"1";
"B"
$PN"2"32;
"A"
$PN"1"43;
%"Q_CAP"
"1","(-1125,3300)","0","pure_quanta","I31";
;
PART_NUMBER"CH6223MEA01"
TOLERANCE"20%"
VALUE"22UF"
PACK_TYPE"C0805"
VOLTAGE"16V"
MATERIAL"X6S"
LOCATION"PC609_P0_2"
CDS_LIB"pure_quanta"
LOCATION"PC609_P0_2"
$SEC"1"
CDS_SEC"1";
"B"
$PN"2"22;
"A"
$PN"1"5;
%"Q_CAP"
"1","(-725,3300)","0","pure_quanta","I32";
;
PART_NUMBER"CH6223MEA01"
TOLERANCE"20%"
VALUE"22UF"
PACK_TYPE"C0805"
MATERIAL"X6S"
VOLTAGE"16V"
LOCATION"PC611_P0_2"
CDS_LIB"pure_quanta"
LOCATION"PC611_P0_2"
$SEC"1"
CDS_SEC"1";
"B"
$PN"2"22;
"A"
$PN"1"5;
%"Q_CAP"
"2","(-3975,5000)","0","pure_quanta","I35";
;
PART_NUMBER"CH4104K1B00"
VALUE"0.1UF"
VOLTAGE"25V"
TOLERANCE"10%"
MATERIAL"X7R"
PACK_TYPE"0402"
LOCATION"PC1349"
CDS_LIB"pure_quanta"
$SEC"1"
CDS_SEC"1";
"A"
$PN"1"15;
"B"
$PN"2"40;
%"Q_CAP"
"1","(-4250,5650)","0","pure_quanta","I37";
;
PART_NUMBER"CH5222KEB01"
VOLTAGE"10V"
VALUE"2.2UF"
TOLERANCE"10%"
MATERIAL"X6S"
PACK_TYPE"C0402"
LOCATION"PC600"
CDS_LIB"pure_quanta"
LOCATION"PC600"
$SEC"1"
CDS_SEC"1";
"B"
$PN"2"20;
"A"
$PN"1"29;
%"UNIVERSAL_GND"
"1","(-4250,5400)","0","logical_power","I38";
;
HDL_POWER"GND"
CDS_LIB"logical_power";
"A"20;
%"Q_RES"
"2","(-4250,6050)","0","pure_quanta","I39";
;
PART_NUMBER"CS-2202FB01"
WATTAGE"1/16W"
PACK_TYPE"0402LF"
VALUE"2.2"
TOLERANCE"1%"
MATERIAL"CHIP"
LOCATION"PR355"
CDS_LIB"pure_quanta"
LOCATION"PR355"
$SEC"1"
CDS_SEC"1";
"A"
$PN"1"39;
"B"
$PN"2"29;
%"Q_RES"
"2","(-4825,3900)","0","pure_quanta","I4";
;
PART_NUMBER"CS00002JB13"
VALUE"0"
TOLERANCE"5%"
MATERIAL"CHIP"
WATTAGE"1/16W"
PACK_TYPE"0402LF"
LOCATION"PR447"
CDS_LIB"pure_quanta"
$SEC"1"
CDS_SEC"1";
"A"
$PN"1"1;
"B"
$PN"2"44;
%"Q_RES"
"2","(-4175,6700)","0","pure_quanta","I40";
;
PART_NUMBER"CS00002JB13"
PACK_TYPE"0402LF"
VALUE"0"
TOLERANCE"5%"
MATERIAL"EMPTY"
WATTAGE"1/16W"
LOCATION"PR632"
CDS_LIB"pure_quanta"
$SEC"1"
CDS_SEC"1";
"A"
$PN"1"4;
"B"
$PN"2"39;
%"UNIVERSAL_GND"
"1","(-3725,5800)","0","logical_power","I41";
;
HDL_POWER"GND"
CDS_LIB"logical_power";
"A"21;
%"Q_CAP"
"1","(-3725,6050)","0","pure_quanta","I42";
;
PART_NUMBER"CH5222KEB01"
VOLTAGE"10V"
TOLERANCE"10%"
PACK_TYPE"C0402"
MATERIAL"X6S"
VALUE"2.2UF"
LOCATION"PC1211_P0_1"
CDS_LIB"pure_quanta"
$SEC"1"
CDS_SEC"1";
"B"
$PN"2"21;
"A"
$PN"1"39;
%"VCC15"
"1","(-4175,6925)","0","logical_power","I43";
;
HDL_POWER"P3V3"
CDS_LIB"logical_power";
"A"4;
%"Q_CAP"
"1","(-1925,6100)","0","pure_quanta","I44";
;
PART_NUMBER"TMP_QCH2336K1B12"
PACK_TYPE"0402"
VOLTAGE"50V"
VALUE"3300PF"
TOLERANCE"10%"
MATERIAL"X7R"
LOCATION"PC602_P0_1"
CDS_LIB"pure_quanta"
LOCATION"PC602_P0_1"
$SEC"1"
CDS_SEC"1";
"B"
$PN"2"26;
"A"
$PN"1"8;
%"Q_CAP"
"1","(-1525,6100)","0","pure_quanta","I45";
;
PART_NUMBER"CH5103KEB01"
VOLTAGE"16V"
VALUE"1UF"
PACK_TYPE"C0402"
TOLERANCE"10%"
MATERIAL"X6S"
LOCATION"PC604_P0_1"
CDS_LIB"pure_quanta"
LOCATION"PC604_P0_1"
$SEC"1"
CDS_SEC"1";
"B"
$PN"2"26;
"A"
$PN"1"8;
%"Q_RES"
"1","(-1225,5650)","0","pure_quanta","I46";
;
PART_NUMBER"CS-3302FB01"
WATTAGE"1/16W"
PACK_TYPE"0402LF"
MATERIAL"CHIP"
VALUE"3.3"
TOLERANCE"1%"
LOCATION"PR1780"
CDS_LIB"pure_quanta"
$SEC"1"
CDS_SEC"1";
"B"
$PN"2"34;
"A"
$PN"1"38;
%"Q_CAP"
"1","(-1125,6100)","0","pure_quanta","I47";
;
PART_NUMBER"CH6223MEA01"
TOLERANCE"20%"
VOLTAGE"16V"
VALUE"22UF"
PACK_TYPE"C0805"
MATERIAL"X6S"
LOCATION"PC608_P0_1"
CDS_LIB"pure_quanta"
LOCATION"PC608_P0_1"
$SEC"1"
CDS_SEC"1";
"B"
$PN"2"26;
"A"
$PN"1"8;
%"Q_CAP"
"1","(-725,6100)","0","pure_quanta","I48";
;
PART_NUMBER"CH6223MEA01"
TOLERANCE"20%"
VOLTAGE"16V"
PACK_TYPE"C0805"
MATERIAL"X6S"
VALUE"22UF"
LOCATION"PC610_P0_1"
CDS_LIB"pure_quanta"
LOCATION"PC610_P0_1"
$SEC"1"
CDS_SEC"1";
"B"
$PN"2"26;
"A"
$PN"1"8;
%"Q_INDUCTOR"
"1","(-25,2425)","0","pure_quanta","I49";
;
PART_NUMBER"CV+13^0KZ11"
PACK_TYPE"SMLF"
VALUE"130NH/106A"
MATERIAL"IND"
LOCATION"PL34"
CDS_LIB"pure_quanta"
NEEDS_NO_SIZE"TRUE"
$SEC"1"
CDS_SEC"1";
"1"
$PN"1"30;
"2"
$PN"2"6;
%"VCC15"
"1","(-4825,4125)","0","logical_power","I5";
;
HDL_POWER"P5V"
CDS_LIB"logical_power";
"A"1;
%"Q_RES"
"1","(-25,2150)","0","pure_quanta","I50";
;
PART_NUMBER"CS00002JB13"
PACK_TYPE"0402LF"
VALUE"0"
TOLERANCE"5%"
MATERIAL"CHIP"
WATTAGE"1/16W"
LOCATION"PR1323"
CDS_LIB"pure_quanta"
$SEC"1"
CDS_SEC"1";
"B"
$PN"2"6;
"A"
$PN"1"36;
%"Q_CAP"
"1","(1000,2200)","0","pure_quanta","I51";
;
PART_NUMBER"CH5103KEB01"
VOLTAGE"16V"
PACK_TYPE"C0402"
TOLERANCE"10%"
MATERIAL"X6S"
VALUE"1UF"
LOCATION"PC613_P0_2"
CDS_LIB"pure_quanta"
LOCATION"PC613_P0_2"
$SEC"1"
CDS_SEC"1";
"B"
$PN"2"23;
"A"
$PN"1"6;
%"Q_CAP"
"1","(1450,2200)","0","pure_quanta","I52";
;
PART_NUMBER"CH622KMEA03"
TOLERANCE"20%"
MATERIAL"X6S"
VOLTAGE"4V"
VALUE"22UF"
PACK_TYPE"C0805"
LOCATION"PC616_P0_2"
CDS_LIB"pure_quanta"
LOCATION"PC616_P0_2"
$SEC"1"
CDS_SEC"1";
"B"
$PN"2"23;
"A"
$PN"1"6;
%"Q_CAP"
"1","(-300,2675)","2","pure_quanta","I53";
;
PART_NUMBER"CH4106K1B01"
PACK_TYPE"C0402"
VOLTAGE"50V"
VALUE"100NF"
TOLERANCE"10%"
MATERIAL"X7R"
LOCATION"PC607"
CDS_LIB"pure_quanta"
$SEC"1"
CDS_SEC"1";
"B"
$PN"2"31;
"A"
$PN"1"32;
%"UNIVERSAL_GND"
"1","(-125,2925)","0","logical_power","I54";
;
HDL_POWER"GND"
CDS_LIB"logical_power";
"A"22;
%"Q_CAP"
"1","(-250,3300)","0","pure_quanta","I55";
;
PART_NUMBER"CH6223MEA01"
TOLERANCE"20%"
MATERIAL"X6S"
VALUE"22UF"
VOLTAGE"16V"
PACK_TYPE"C0805"
LOCATION"PC721_P0_2"
CDS_LIB"pure_quanta"
$SEC"1"
CDS_SEC"1";
"B"
$PN"2"22;
"A"
$PN"1"5;
%"VCC15"
"1","(-125,3675)","0","logical_power","I56";
;
HDL_POWER"SW_P12V_PVCCFA_EHV_FIVRA_CPU0_L"
CDS_LIB"logical_power";
"A"5;
%"Q_CAPP"
"1","(1175,3325)","0","pure_quanta","I57";
;
PART_NUMBER"CC7560JMD16"
PACK_TYPE"THLF"
VALUE"560UF"
TOLERANCE"20%"
MATERIAL"OSCON"
VOLTAGE"2.5V"
LOCATION"PC619"
CDS_LIB"pure_quanta"
LOCATION"PC619"
$SEC"1"
CDS_SEC"1";
"A"
$PN"1"7;
"B"
$PN"2"25;
%"Q_CAPP"
"1","(1700,3325)","0","pure_quanta","I58";
;
PART_NUMBER"CC7560JMD16"
PACK_TYPE"THLF"
VALUE"560UF"
TOLERANCE"20%"
MATERIAL"OSCON"
VOLTAGE"2.5V"
LOCATION"PC620"
CDS_LIB"pure_quanta"
LOCATION"PC620"
$SEC"1"
CDS_SEC"1";
"A"
$PN"1"7;
"B"
$PN"2"25;
%"Q_CAP"
"1","(1875,2200)","0","pure_quanta","I59";
;
PART_NUMBER"CH622KMEA03"
TOLERANCE"20%"
VALUE"22UF"
VOLTAGE"4V"
PACK_TYPE"C0805"
MATERIAL"X6S"
LOCATION"PC618_P0_2"
CDS_LIB"pure_quanta"
LOCATION"PC618_P0_2"
$SEC"1"
CDS_SEC"1";
"B"
$PN"2"23;
"A"
$PN"1"6;
%"UNIVERSAL_GND"
"1","(-4725,4525)","0","logical_power","I6";
;
HDL_POWER"GND"
CDS_LIB"logical_power";
"A"14;
%"Q_RES"
"2","(2300,2200)","0","pure_quanta","I60";
;
PART_NUMBER"CS14992FB06"
MATERIAL"CHIP"
VALUE"499"
PACK_TYPE"0402LF"
TOLERANCE"1%"
WATTAGE"1/16W"
LOCATION"PR4265"
CDS_LIB"pure_quanta"
BOM_COST"VR_PCH"
$SEC"1"
CDS_SEC"1";
"A"
$PN"1"6;
"B"
$PN"2"23;
%"UNIVERSAL_GND"
"1","(2700,1775)","0","logical_power","I61";
;
HDL_POWER"GND"
CDS_LIB"logical_power";
"A"23;
%"Q_CAPP"
"1","(2225,3325)","0","pure_quanta","I62";
;
PART_NUMBER"CC7560JMD16"
MATERIAL"OSCON"
VOLTAGE"2.5V"
PACK_TYPE"THLF"
VALUE"560UF"
TOLERANCE"20%"
LOCATION"PC621"
CDS_LIB"pure_quanta"
LOCATION"PC621"
$SEC"1"
CDS_SEC"1";
"A"
$PN"1"7;
"B"
$PN"2"25;
%"Q_CAPP"
"1","(2725,3325)","0","pure_quanta","I63";
;
PART_NUMBER"CH733LY8802"
VOLTAGE"2.5V"
MATERIAL"SPCAP"
PACK_TYPE"SMLF"
VALUE"330UF"
TOLERANCE"+10/-35%"
LOCATION"PC623"
CDS_LIB"pure_quanta"
LOCATION"PC623"
$SEC"1"
CDS_SEC"1";
"A"
$PN"1"7;
"B"
$PN"2"25;
%"UNIVERSAL_GND"
"1","(2175,4625)","0","logical_power","I64";
;
HDL_POWER"GND"
CDS_LIB"logical_power";
"A"24;
%"VCC15"
"1","(2700,2625)","0","logical_power","I65";
;
HDL_POWER"PVCCFA_EHV_FIVRA_CPU0"
CDS_LIB"logical_power";
"A"6;
%"UNIVERSAL_GND"
"1","(3175,2975)","0","logical_power","I66";
;
HDL_POWER"GND"
CDS_LIB"logical_power";
"A"25;
%"Q_CAPP"
"1","(3175,3325)","0","pure_quanta","I67";
;
PART_NUMBER"CH733LY8802"
MATERIAL"SPCAP"
TOLERANCE"+10/-35%"
PACK_TYPE"SMLF"
VOLTAGE"2.5V"
VALUE"330UF"
LOCATION"PC2645"
CDS_LIB"pure_quanta"
$SEC"1"
CDS_SEC"1";
"A"
$PN"1"7;
"B"
$PN"2"25;
%"VCC15"
"1","(3175,3650)","0","logical_power","I68";
;
HDL_POWER"PVCCFA_EHV_FIVRA_CPU0"
CDS_LIB"logical_power";
"A"7;
%"Q_RES"
"1","(-25,4950)","0","pure_quanta","I69";
;
PART_NUMBER"CS00002JB13"
WATTAGE"1/16W"
MATERIAL"CHIP"
PACK_TYPE"0402LF"
VALUE"0"
TOLERANCE"5%"
LOCATION"PR1322"
CDS_LIB"pure_quanta"
$SEC"1"
CDS_SEC"1";
"B"
$PN"2"10;
"A"
$PN"1"33;
%"UNIVERSAL_GND"
"1","(-4800,4925)","0","logical_power","I7";
;
HDL_POWER"GND"
CDS_LIB"logical_power";
"A"15;
%"Q_INDUCTOR"
"1","(-25,5225)","0","pure_quanta","I70";
;
PART_NUMBER"CV+13^0KZ11"
PACK_TYPE"SMLF"
VALUE"130NH/106A"
MATERIAL"IND"
LOCATION"PL33"
CDS_LIB"pure_quanta"
NEEDS_NO_SIZE"TRUE"
$SEC"1"
CDS_SEC"1";
"1"
$PN"1"35;
"2"
$PN"2"10;
%"Q_CAP"
"1","(-300,5475)","2","pure_quanta","I71";
;
PART_NUMBER"CH4106K1B01"
PACK_TYPE"C0402"
TOLERANCE"10%"
MATERIAL"X7R"
VALUE"100NF"
VOLTAGE"50V"
LOCATION"PC606"
CDS_LIB"pure_quanta"
$SEC"1"
CDS_SEC"1";
"B"
$PN"2"37;
"A"
$PN"1"34;
%"UNIVERSAL_GND"
"1","(-125,5725)","0","logical_power","I72";
;
HDL_POWER"GND"
CDS_LIB"logical_power";
"A"26;
%"Q_CAP"
"1","(-300,6125)","0","pure_quanta","I73";
;
PART_NUMBER"CH6223MEA01"
TOLERANCE"20%"
PACK_TYPE"C0805"
VOLTAGE"16V"
VALUE"22UF"
MATERIAL"X6S"
LOCATION"PC720_P0_1"
CDS_LIB"pure_quanta"
$SEC"1"
CDS_SEC"1";
"B"
$PN"2"26;
"A"
$PN"1"8;
%"VCC15"
"1","(-125,6475)","0","logical_power","I74";
;
HDL_POWER"SW_P12V_PVCCFA_EHV_FIVRA_CPU0_R"
CDS_LIB"logical_power";
"A"8;
%"Q_CAP"
"1","(950,5000)","0","pure_quanta","I75";
;
PART_NUMBER"CH4106K1B01"
VOLTAGE"50V"
TOLERANCE"10%"
MATERIAL"X7R"
PACK_TYPE"C0402"
VALUE"100NF"
LOCATION"PC612_P0_1"
CDS_LIB"pure_quanta"
LOCATION"PC612_P0_1"
$SEC"1"
CDS_SEC"1";
"B"
$PN"2"24;
"A"
$PN"1"10;
%"GND"
"1","(1000,5625)","0","logical_power","I76";
;
HDL_POWER"GND"
CDS_LIB"logical_power"
SIZE"1B";
"A<SIZE-1..0>\NAC"27;
%"Q_CAP"
"1","(1450,5000)","0","pure_quanta","I77";
;
PART_NUMBER"CH622KMEA03"
TOLERANCE"20%"
PACK_TYPE"C0805"
MATERIAL"X6S"
VALUE"22UF"
VOLTAGE"4V"
LOCATION"PC615_P0_1"
CDS_LIB"pure_quanta"
LOCATION"PC615_P0_1"
$SEC"1"
CDS_SEC"1";
"B"
$PN"2"24;
"A"
$PN"1"10;
%"Q_CAP"
"1","(1000,5875)","0","pure_quanta","I78";
;
PART_NUMBER"CH4106K1B01"
TOLERANCE"10%"
VALUE"100NF"
VOLTAGE"50V"
MATERIAL"X7R"
PACK_TYPE"C0402"
LOCATION"PC1653"
CDS_LIB"pure_quanta"
$SEC"1"
CDS_SEC"1";
"B"
$PN"2"27;
"A"
$PN"1"9;
%"VCC15"
"1","(1000,6250)","0","logical_power","I79";
;
HDL_POWER"P12V_AUX"
CDS_LIB"logical_power";
"A"9;
%"Q_RES"
"2","(-4725,4750)","2","pure_quanta","I8";
;
PART_NUMBER"CS28872FB01"
VALUE"8.87K"
TOLERANCE"1%"
WATTAGE"1/16W"
PACK_TYPE"0402LF"
MATERIAL"EMPTY"
LOCATION"PR354"
CDS_LIB"pure_quanta"
LOCATION"PR354"
$SEC"1"
CDS_SEC"1";
"A"
$PN"1"51;
"B"
$PN"2"14;
%"Q_INDUCTOR"
"1","(1425,6100)","0","pure_quanta","I80";
;
PART_NUMBER"CV+10G0MZ04"
PACK_TYPE"SMLF"
MATERIAL"IND"
VALUE"100NH/16A"
LOCATION"PL44"
CDS_LIB"pure_quanta"
NEEDS_NO_SIZE"TRUE"
$SEC"1"
CDS_SEC"1";
"1"
$PN"1"9;
"2"
$PN"2"11;
%"Q_CAP"
"1","(1875,5000)","0","pure_quanta","I81";
;
PART_NUMBER"CH622KMEA03"
TOLERANCE"20%"
PACK_TYPE"C0805"
VOLTAGE"4V"
VALUE"22UF"
MATERIAL"X6S"
LOCATION"PC617_P0_1"
CDS_LIB"pure_quanta"
LOCATION"PC617_P0_1"
$SEC"1"
CDS_SEC"1";
"B"
$PN"2"24;
"A"
$PN"1"10;
%"VCC15"
"1","(2175,5400)","0","logical_power","I82";
;
HDL_POWER"PVCCFA_EHV_FIVRA_CPU0"
CDS_LIB"logical_power";
"A"10;
%"Q_CAP"
"1","(1775,5850)","0","pure_quanta","I83";
;
PART_NUMBER"CH6223MEA01"
TOLERANCE"20%"
VOLTAGE"16V"
MATERIAL"X6S"
PACK_TYPE"C0805"
VALUE"22UF"
LOCATION"PC1669"
CDS_LIB"pure_quanta"
$SEC"1"
CDS_SEC"1";
"B"
$PN"2"28;
"A"
$PN"1"11;
%"Q_CAP"
"1","(2075,5850)","0","pure_quanta","I84";
;
PART_NUMBER"CH6223MEA01"
TOLERANCE"20%"
VALUE"22UF"
MATERIAL"X6S"
PACK_TYPE"C0805"
VOLTAGE"16V"
LOCATION"PC1670"
CDS_LIB"pure_quanta"
$SEC"1"
CDS_SEC"1";
"B"
$PN"2"28;
"A"
$PN"1"11;
%"Q_CAP"
"1","(2350,5850)","0","pure_quanta","I85";
;
PART_NUMBER"CH6223MEA01"
TOLERANCE"20%"
MATERIAL"X6S"
VALUE"22UF"
VOLTAGE"16V"
PACK_TYPE"C0805"
LOCATION"PC1671"
CDS_LIB"pure_quanta"
$SEC"1"
CDS_SEC"1";
"B"
$PN"2"28;
"A"
$PN"1"11;
%"Q_CAP"
"1","(2625,5850)","0","pure_quanta","I86";
;
PART_NUMBER"CH6223MEA01"
TOLERANCE"20%"
PACK_TYPE"C0805"
MATERIAL"X6S"
VOLTAGE"16V"
VALUE"22UF"
LOCATION"PC1672"
CDS_LIB"pure_quanta"
$SEC"1"
CDS_SEC"1";
"B"
$PN"2"28;
"A"
$PN"1"11;
%"UNIVERSAL_GND"
"1","(2900,5575)","0","logical_power","I87";
;
HDL_POWER"GND"
CDS_LIB"logical_power";
"A"28;
%"Q_CAPP"
"1","(2900,5850)","0","pure_quanta","I88";
;
PART_NUMBER"CC72703MD38"
PACK_TYPE"THLF"
TOLERANCE"20%"
MATERIAL"OSCON"
VALUE"270UF"
VOLTAGE"16V"
LOCATION"PC622"
CDS_LIB"pure_quanta"
LOCATION"PC622"
$SEC"1"
CDS_SEC"1";
"A"
$PN"1"11;
"B"
$PN"2"28;
%"VCC15"
"1","(3025,6225)","0","logical_power","I89";
;
HDL_POWER"SW_P12V_PVCCFA_EHV_FIVRA_CPU0_L"
CDS_LIB"logical_power";
"A"11;
%"Q_RES"
"2","(-4825,6700)","0","pure_quanta","I9";
;
PART_NUMBER"CS00002JB13"
PACK_TYPE"0402LF"
VALUE"0"
TOLERANCE"5%"
MATERIAL"CHIP"
WATTAGE"1/16W"
LOCATION"PR444"
CDS_LIB"pure_quanta"
$SEC"1"
CDS_SEC"1";
"A"
$PN"1"2;
"B"
$PN"2"39;
END.
